# S9S_MB_2U (Grand Teton) — schematic netlist excerpt (pin names and nets, part order shuffled) for the footprints in the layout excerpt that follows; sources: Cadence DE-HDL packaged netlist, KiCad conversion of 03242023_DA0F0TMBIJ0_F0T_Motherboard_J_brd_V01_OCP.brd

C414  Q_CAP  22UF 4V 20% X6S  pkg C0402  page 74 : A = PVCCINFAON_CPU0 ; B = GND
R4458  Q_RES  10K 1% EMPTY  pkg 0402LF  page 196 : A = P3V3_AUX ; B = USB_HUB_2_OVCUR3

(kicad_pcb
	(version 20260206)
	(generator "pcbnew")
	(generator_version "10.0")
	(general
		(thickness 1.6)
		(legacy_teardrops no)
	)
	(paper "A4")
	(title_block
		(title "03242023_DA0F0TMBIJ0_F0T_Motherboard_J_brd_V01_OCP.brd")
		(comment 1 "Grand Teton / footprints 4003-4004 of 6105")
	)
	(layers
		(0 "F.Cu" signal "TOP")
		(4 "In1.Cu" signal "GND")
		(6 "In2.Cu" signal "IN1")
		(8 "In3.Cu" signal "GND1")
		(10 "In4.Cu" signal "IN2")
		(12 "In5.Cu" signal "GND2")
		(14 "In6.Cu" signal "IN3")
		(16 "In7.Cu" signal "GND3")
		(18 "In8.Cu" signal "VCC")
		(20 "In9.Cu" signal "VCC1")
		(22 "In10.Cu" signal "GND4")
		(24 "In11.Cu" signal "IN4")
		(26 "In12.Cu" signal "GND5")
		(28 "In13.Cu" signal "IN5")
		(30 "In14.Cu" signal "GND6")
		(32 "In15.Cu" signal "IN6")
		(34 "In16.Cu" signal "GND7")
		(2 "B.Cu" signal "BOTTOM")
		(9 "F.Adhes" user "F.Adhesive")
		(11 "B.Adhes" user "B.Adhesive")
		(13 "F.Paste" user "Package Geometry/Pastemask Top")
		(15 "B.Paste" user "Package Geometry/Pastemask Bottom")
		(5 "F.SilkS" user "Ref Des/Silkscreen Top")
		(7 "B.SilkS" user "Ref Des/Silkscreen Bottom")
		(1 "F.Mask" user "Board Geometry/Soldermask Top")
		(3 "B.Mask" user "Board Geometry/Soldermask Bottom")
		(17 "Dwgs.User" user "User.Drawings")
		(19 "Cmts.User" user "User.Comments")
		(21 "Eco1.User" user "User.Eco1")
		(23 "Eco2.User" user "User.Eco2")
		(25 "Edge.Cuts" user "Board Geometry/Outline")
		(27 "Margin" user)
		(31 "F.CrtYd" user "Package Geometry/Place Bound Top")
		(29 "B.CrtYd" user "Package Geometry/Place Bound Bottom")
		(35 "F.Fab" user "Ref Des/Assembly Top")
		(33 "B.Fab" user "Ref Des/Assembly Bottom")
	)
	(footprint ""
		(layer "F.Cu")
		(at 367.44783 -260.364986 -90)
		(property "Reference" "C414"
			(at 0 0 270)
			(layer "F.SilkS")
			(hide yes)
			(effects
				(font
					(size 1.27 1.27)
				)
			)
		)
		(property "Value" ""
			(at 0 0 270)
			(layer "F.Fab")
			(effects
				(font
					(size 1.27 1.27)
				)
			)
		)
		(duplicate_pad_numbers_are_jumpers no)
		(fp_line
			(start -0.7874 0.4064)
			(end -0.7874 -0.4064)
			(stroke
				(width 0.1524)
				(type default)
			)
			(layer "F.SilkS")
		)
		(fp_line
			(start 0.7874 0.4064)
			(end -0.7874 0.4064)
			(stroke
				(width 0.1524)
				(type default)
			)
			(layer "F.SilkS")
		)
		(fp_line
			(start -0.7874 -0.4064)
			(end 0.7874 -0.4064)
			(stroke
				(width 0.1524)
				(type default)
			)
			(layer "F.SilkS")
		)
		(fp_line
			(start 0.7874 -0.4064)
			(end 0.7874 0.4064)
			(stroke
				(width 0.1524)
				(type default)
			)
			(layer "F.SilkS")
		)
		(fp_line
			(start -0.67945 0.3048)
			(end -0.67945 -0.305054)
			(stroke
				(width 0.1)
				(type default)
			)
			(layer "F.Fab")
		)
		(fp_line
			(start -0.12065 0.3048)
			(end -0.67945 0.3048)
			(stroke
				(width 0.1)
				(type default)
			)
			(layer "F.Fab")
		)
		(fp_line
			(start 0.120396 0.3048)
			(end 0.120396 0.2794)
			(stroke
				(width 0.1)
				(type default)
			)
			(layer "F.Fab")
		)
		(fp_line
			(start 0.67945 0.3048)
			(end 0.120396 0.3048)
			(stroke
				(width 0.1)
				(type default)
			)
			(layer "F.Fab")
		)
		(fp_line
			(start -0.12065 0.2794)
			(end -0.12065 0.3048)
			(stroke
				(width 0.1)
				(type default)
			)
			(layer "F.Fab")
		)
		(fp_line
			(start 0.120396 0.2794)
			(end -0.12065 0.2794)
			(stroke
				(width 0.1)
				(type default)
			)
			(layer "F.Fab")
		)
		(fp_line
			(start -0.12065 -0.2794)
			(end 0.12065 -0.2794)
			(stroke
				(width 0.1)
				(type default)
			)
			(layer "F.Fab")
		)
		(fp_line
			(start 0.12065 -0.2794)
			(end 0.12065 -0.3048)
			(stroke
				(width 0.1)
				(type default)
			)
			(layer "F.Fab")
		)
		(fp_line
			(start 0.12065 -0.3048)
			(end 0.67945 -0.3048)
			(stroke
				(width 0.1)
				(type default)
			)
			(layer "F.Fab")
		)
		(fp_line
			(start 0.67945 -0.3048)
			(end 0.67945 0.3048)
			(stroke
				(width 0.1)
				(type default)
			)
			(layer "F.Fab")
		)
		(fp_line
			(start -0.67945 -0.305054)
			(end -0.12065 -0.305054)
			(stroke
				(width 0.1)
				(type default)
			)
			(layer "F.Fab")
		)
		(fp_line
			(start -0.12065 -0.305054)
			(end -0.12065 -0.2794)
			(stroke
				(width 0.1)
				(type default)
			)
			(layer "F.Fab")
		)
		(pad "1" smd circle
			(at -0.40005 0 270)
			(size 0 0)
			(layers "F.Cu" "F.Mask" "F.Paste")
			(net "PVCCINFAON_CPU0")
		)
		(pad "2" smd circle
			(at 0.40005 0 270)
			(size 0 0)
			(layers "F.Cu" "F.Mask" "F.Paste")
			(net "GND")
		)
	)
	(footprint ""
		(layer "F.Cu")
		(at 159.181546 -31.341568 90)
		(property "Reference" "R4458"
			(at 0 0 90)
			(layer "F.SilkS")
			(hide yes)
			(effects
				(font
					(size 1.27 1.27)
				)
			)
		)
		(property "Value" ""
			(at 0 0 90)
			(layer "F.Fab")
			(effects
				(font
					(size 1.27 1.27)
				)
			)
		)
		(duplicate_pad_numbers_are_jumpers no)
		(fp_line
			(start 0.7874 -0.4064)
			(end 0.7874 0.4064)
			(stroke
				(width 0.1524)
				(type default)
			)
			(layer "F.SilkS")
		)
		(fp_line
			(start -0.7874 -0.4064)
			(end 0.7874 -0.4064)
			(stroke
				(width 0.1524)
				(type default)
			)
			(layer "F.SilkS")
		)
		(fp_line
			(start 0.7874 0.4064)
			(end -0.7874 0.4064)
			(stroke
				(width 0.1524)
				(type default)
			)
			(layer "F.SilkS")
		)
		(fp_line
			(start -0.7874 0.4064)
			(end -0.7874 -0.4064)
			(stroke
				(width 0.1524)
				(type default)
			)
			(layer "F.SilkS")
		)
		(fp_line
			(start -0.12065 -0.305054)
			(end -0.12065 -0.2794)
			(stroke
				(width 0.1)
				(type default)
			)
			(layer "F.Fab")
		)
		(fp_line
			(start -0.67945 -0.305054)
			(end -0.12065 -0.305054)
			(stroke
				(width 0.1)
				(type default)
			)
			(layer "F.Fab")
		)
		(fp_line
			(start 0.67945 -0.3048)
			(end 0.67945 0.3048)
			(stroke
				(width 0.1)
				(type default)
			)
			(layer "F.Fab")
		)
		(fp_line
			(start 0.12065 -0.3048)
			(end 0.67945 -0.3048)
			(stroke
				(width 0.1)
				(type default)
			)
			(layer "F.Fab")
		)
		(fp_line
			(start 0.12065 -0.2794)
			(end 0.12065 -0.3048)
			(stroke
				(width 0.1)
				(type default)
			)
			(layer "F.Fab")
		)
		(fp_line
			(start -0.12065 -0.2794)
			(end 0.12065 -0.2794)
			(stroke
				(width 0.1)
				(type default)
			)
			(layer "F.Fab")
		)
		(fp_line
			(start 0.120396 0.2794)
			(end -0.12065 0.2794)
			(stroke
				(width 0.1)
				(type default)
			)
			(layer "F.Fab")
		)
		(fp_line
			(start -0.12065 0.2794)
			(end -0.12065 0.3048)
			(stroke
				(width 0.1)
				(type default)
			)
			(layer "F.Fab")
		)
		(fp_line
			(start 0.67945 0.3048)
			(end 0.120396 0.3048)
			(stroke
				(width 0.1)
				(type default)
			)
			(layer "F.Fab")
		)
		(fp_line
			(start 0.120396 0.3048)
			(end 0.120396 0.2794)
			(stroke
				(width 0.1)
				(type default)
			)
			(layer "F.Fab")
		)
		(fp_line
			(start -0.12065 0.3048)
			(end -0.67945 0.3048)
			(stroke
				(width 0.1)
				(type default)
			)
			(layer "F.Fab")
		)
		(fp_line
			(start -0.67945 0.3048)
			(end -0.67945 -0.305054)
			(stroke
				(width 0.1)
				(type default)
			)
			(layer "F.Fab")
		)
		(pad "1" smd circle
			(at -0.40005 0 90)
			(size 0 0)
			(layers "F.Cu" "F.Mask" "F.Paste")
			(net "P3V3_AUX")
		)
		(pad "2" smd circle
			(at 0.40005 0 90)
			(size 0 0)
			(layers "F.Cu" "F.Mask" "F.Paste")
			(net "USB_HUB_2_OVCUR3")
		)
	)
)
